# TIMECARD (Time Appliance Project (Time Card)) — schematic netlist excerpt (pin names and nets, part order shuffled) for the footprints in the layout excerpt that follows; sources: Cadence DE-HDL packaged netlist, KiCad conversion of R4006-B0001-02_R01.brd

ME2  NUT  pkg P_NUT_166CT244CB198_V1_H380  page 34 : \1\ = SG
TP36  TP_PIONT  pkg TP010CT020B030_PTH  page 25 : \1\ = XP12R0V_A_PG

(kicad_pcb
	(version 20260206)
	(generator "pcbnew")
	(generator_version "10.0")
	(general
		(thickness 1.6)
		(legacy_teardrops no)
	)
	(paper "A4")
	(title_block
		(title "timecard-production-celestica-r4006 — R4006-B0001-02_R01.brd")
		(comment 1 "Time Appliance Project (Time Card) / footprints 474-475 of 1113")
	)
	(layers
		(0 "F.Cu" signal "TOP")
		(4 "In1.Cu" signal "L02_GND1")
		(6 "In2.Cu" signal "L03_SIG1")
		(8 "In3.Cu" signal "L04_GND2")
		(10 "In4.Cu" signal "L05_VCC1")
		(12 "In5.Cu" signal "L06_VCC2")
		(14 "In6.Cu" signal "L07_GND3")
		(16 "In7.Cu" signal "L08_SIG2")
		(18 "In8.Cu" signal "L09_GND4")
		(2 "B.Cu" signal "BOTTOM")
		(9 "F.Adhes" user "F.Adhesive")
		(11 "B.Adhes" user "B.Adhesive")
		(13 "F.Paste" user "Package Geometry/Pastemask Top")
		(15 "B.Paste" user "Package Geometry/Pastemask Bottom")
		(5 "F.SilkS" user "Ref Des/Silkscreen Top")
		(7 "B.SilkS" user "Ref Des/Silkscreen Bottom")
		(1 "F.Mask" user "Board Geometry/Soldermask Top")
		(3 "B.Mask" user "Board Geometry/Soldermask Bottom")
		(17 "Dwgs.User" user "User.Drawings")
		(19 "Cmts.User" user "User.Comments")
		(21 "Eco1.User" user "User.Eco1")
		(23 "Eco2.User" user "User.Eco2")
		(25 "Edge.Cuts" user "Board Geometry/Outline")
		(27 "Margin" user)
		(31 "F.CrtYd" user "Package Geometry/Place Bound Top")
		(29 "B.CrtYd" user "Package Geometry/Place Bound Bottom")
		(35 "F.Fab" user "Ref Des/Assembly Top")
		(33 "B.Fab" user "Ref Des/Assembly Bottom")
	)
	(footprint ""
		(layer "F.Cu")
		(at 65.000124 -78.650084)
		(property "Reference" "ME2"
			(at -0.928624 -4.368546 0)
			(unlocked yes)
			(layer "F.SilkS")
			(effects
				(font
					(size 0.7874 0.5842)
					(thickness 0.1524)
				)
				(justify left)
			)
		)
		(property "Value" ""
			(at 0 0 0)
			(layer "F.Fab")
			(effects
				(font
					(size 1.27 1.27)
				)
			)
		)
		(property "User Part Number" "PARTNUM*"
			(at -3.048 5.242306 0)
			(unlocked yes)
			(layer "Cmts.User")
			(hide yes)
			(effects
				(font
					(size 0.7874 0.5842)
					(thickness 0.1524)
				)
				(justify left)
			)
		)
		(property "Device Type" "NUT-G340-10437-01"
			(at -1.4732 4.226306 0)
			(unlocked yes)
			(layer "F.Fab")
			(hide yes)
			(effects
				(font
					(size 0.7874 0.5842)
					(thickness 0.1524)
				)
				(justify left)
			)
		)
		(duplicate_pad_numbers_are_jumpers no)
		(fp_circle
			(center 0 0)
			(end 3.3528 0)
			(stroke
				(width 0.1)
				(type default)
			)
			(fill no)
			(layer "F.SilkS")
		)
		(fp_poly
			(pts
				(arc
					(start -2.102612 -0.1524)
					(mid -1.490671 -1.490671)
					(end -0.1524 -2.102612)
				)
				(arc
					(start -0.1524 -3.171444)
					(mid -2.245137 -2.245137)
					(end -3.171444 -0.1524)
				)
			)
			(stroke
				(width 0)
				(type default)
			)
			(fill yes)
			(layer "F.Paste")
		)
		(fp_poly
			(pts
				(arc
					(start -0.1524 2.102612)
					(mid -1.490671 1.490671)
					(end -2.102612 0.1524)
				)
				(arc
					(start -3.171444 0.1524)
					(mid -2.245137 2.245137)
					(end -0.1524 3.171444)
				)
			)
			(stroke
				(width 0)
				(type default)
			)
			(fill yes)
			(layer "F.Paste")
		)
		(fp_poly
			(pts
				(arc
					(start 0.1524 -2.102612)
					(mid 1.490671 -1.490671)
					(end 2.102612 -0.1524)
				)
				(arc
					(start 3.171444 -0.1524)
					(mid 2.245137 -2.245137)
					(end 0.1524 -3.171444)
				)
			)
			(stroke
				(width 0)
				(type default)
			)
			(fill yes)
			(layer "F.Paste")
		)
		(fp_poly
			(pts
				(arc
					(start 2.102612 0.1524)
					(mid 1.490671 1.490671)
					(end 0.1524 2.102612)
				)
				(arc
					(start 0.1524 3.171444)
					(mid 2.245137 2.245137)
					(end 3.171444 0.1524)
				)
			)
			(stroke
				(width 0)
				(type default)
			)
			(fill yes)
			(layer "F.Paste")
		)
		(fp_rect
			(start -7.5946 7.5946)
			(end 7.5946 -7.5946)
			(stroke
				(width 0)
				(type default)
			)
			(fill no)
			(layer "B.CrtYd")
		)
		(fp_poly
			(pts
				(arc
					(start 3.6068 0)
					(mid -3.6068 0)
					(end 3.6068 0)
				)
			)
			(stroke
				(width 0)
				(type default)
			)
			(fill no)
			(layer "F.CrtYd")
		)
		(fp_circle
			(center 0 0)
			(end 2.8448 0)
			(stroke
				(width 0.1)
				(type default)
			)
			(fill no)
			(layer "F.Fab")
		)
		(pad "1" thru_hole circle
			(at 0 0)
			(size 6.1976 6.1976)
			(drill 4.2164)
			(layers "*.Cu" "*.Mask")
			(remove_unused_layers no)
			(net "SG")
			(padstack
				(mode front_inner_back)
				(layer "Inner"
					(shape circle)
					(size 5.0292 5.0292)
					(clearance -0.1143)
				)
				(layer "B.Cu"
					(shape circle)
					(size 5.0292 5.0292)
				)
			)
		)
	)
	(footprint ""
		(layer "F.Cu")
		(at 142.24 -101.854)
		(property "Reference" "TP36"
			(at 0.4826 0.15875 0)
			(unlocked yes)
			(layer "F.SilkS")
			(effects
				(font
					(size 0.635 0.4064)
					(thickness 0.1524)
				)
				(justify left)
			)
		)
		(property "Value" ""
			(at 0 0 0)
			(layer "F.Fab")
			(effects
				(font
					(size 1.27 1.27)
				)
			)
		)
		(property "Device Type" "TP_PIONT-TP010CT020B030_PTH-TPA"
			(at -1.341882 0.996696 0)
			(unlocked yes)
			(layer "F.Fab")
			(hide yes)
			(effects
				(font
					(size 0.7874 0.5842)
					(thickness 0.000001)
				)
				(justify left)
			)
		)
		(duplicate_pad_numbers_are_jumpers no)
		(fp_poly
			(pts
				(arc
					(start 0.889 0)
					(mid -0.889 0)
					(end 0.889 0)
				)
			)
			(stroke
				(width 0)
				(type default)
			)
			(fill no)
			(layer "B.CrtYd")
		)
		(fp_poly
			(pts
				(arc
					(start 0.889 0)
					(mid -0.889 0)
					(end 0.889 0)
				)
			)
			(stroke
				(width 0)
				(type default)
			)
			(fill no)
			(layer "F.CrtYd")
		)
		(pad "1" thru_hole circle
			(at 0 0)
			(size 0.508 0.508)
			(drill 0.254)
			(layers "*.Cu" "*.Mask")
			(remove_unused_layers no)
			(net "XP12R0V_A_PG")
			(clearance 0.1016)
			(padstack
				(mode front_inner_back)
				(layer "Inner"
					(shape circle)
					(size 0.508 0.508)
					(clearance 0.1016)
				)
				(layer "B.Cu"
					(shape circle)
					(size 0.762 0.762)
					(clearance -0.0254)
				)
			)
		)
	)
)
